# T6G (Grand Teton) — schematic netlist excerpt (pin names and nets, part order shuffled) for the footprints in the layout excerpt that follows; sources: Cadence DE-HDL packaged netlist, KiCad conversion of 04192023_DAF0TMB3IC0_F0TG_MB_C_brd_V02_OCP.brd

C6715  Q_CAP_DIFFBUS  DIFF BUS_0.22UF 6.3V 20% X6S  pkg C0201  page 341 : \1\ = P5E_CPU1_P2_TX_BUF_C_DP<11> ; \2\ = P5E_CPU1_P2_TX_BUF_DP<11>
R3478  Q_RES  33.2 1% CHIP  pkg 0402LF  page 81 : A = GPU_FPGA_EROT_RST_N ; B = GPU_FPGA_EROT_RST_R_N
R6110  Q_RES  0 5% CHIP  pkg 0402LF  page 174 : A = JTAG_CPUX_TDO_R ; B = JTAG_CPUX_TDO

(kicad_pcb
	(version 20260206)
	(generator "pcbnew")
	(generator_version "10.0")
	(general
		(thickness 1.6)
		(legacy_teardrops no)
	)
	(paper "A4")
	(title_block
		(title "04192023_DAF0TMB3IC0_F0TG_MB_C_brd_V02_OCP.brd")
		(comment 1 "Grand Teton / footprints 651-653 of 8354")
	)
	(layers
		(0 "F.Cu" signal "TOP")
		(4 "In1.Cu" signal "GND")
		(6 "In2.Cu" signal "IN1")
		(8 "In3.Cu" signal "GND1")
		(10 "In4.Cu" signal "IN2")
		(12 "In5.Cu" signal "GND2")
		(14 "In6.Cu" signal "IN3")
		(16 "In7.Cu" signal "GND3")
		(18 "In8.Cu" signal "VCC")
		(20 "In9.Cu" signal "VCC1")
		(22 "In10.Cu" signal "GND4")
		(24 "In11.Cu" signal "IN4")
		(26 "In12.Cu" signal "GND5")
		(28 "In13.Cu" signal "IN5")
		(30 "In14.Cu" signal "GND6")
		(32 "In15.Cu" signal "IN6")
		(34 "In16.Cu" signal "GND7")
		(2 "B.Cu" signal "BOTTOM")
		(9 "F.Adhes" user "F.Adhesive")
		(11 "B.Adhes" user "B.Adhesive")
		(13 "F.Paste" user "Package Geometry/Pastemask Top")
		(15 "B.Paste" user "Package Geometry/Pastemask Bottom")
		(5 "F.SilkS" user "Ref Des/Silkscreen Top")
		(7 "B.SilkS" user "Ref Des/Silkscreen Bottom")
		(1 "F.Mask" user "Board Geometry/Soldermask Top")
		(3 "B.Mask" user "Board Geometry/Soldermask Bottom")
		(17 "Dwgs.User" user "User.Drawings")
		(19 "Cmts.User" user "User.Comments")
		(21 "Eco1.User" user "User.Eco1")
		(23 "Eco2.User" user "User.Eco2")
		(25 "Edge.Cuts" user "Board Geometry/Outline")
		(27 "Margin" user)
		(31 "F.CrtYd" user "Package Geometry/Place Bound Top")
		(29 "B.CrtYd" user "Package Geometry/Place Bound Bottom")
		(35 "F.Fab" user "Ref Des/Assembly Top")
		(33 "B.Fab" user "Ref Des/Assembly Bottom")
	)
	(footprint ""
		(layer "F.Cu")
		(at 200.952608 -110.577376 180)
		(property "Reference" "R3478"
			(at 0 0 180)
			(layer "F.SilkS")
			(hide yes)
			(effects
				(font
					(size 1.27 1.27)
				)
			)
		)
		(property "Value" ""
			(at 0 0 180)
			(layer "F.Fab")
			(effects
				(font
					(size 1.27 1.27)
				)
			)
		)
		(duplicate_pad_numbers_are_jumpers no)
		(fp_line
			(start 0.7874 0.4064)
			(end -0.7874 0.4064)
			(stroke
				(width 0.1524)
				(type default)
			)
			(layer "F.SilkS")
		)
		(fp_line
			(start 0.7874 -0.4064)
			(end 0.7874 0.4064)
			(stroke
				(width 0.1524)
				(type default)
			)
			(layer "F.SilkS")
		)
		(fp_line
			(start -0.7874 0.4064)
			(end -0.7874 -0.4064)
			(stroke
				(width 0.1524)
				(type default)
			)
			(layer "F.SilkS")
		)
		(fp_line
			(start -0.7874 -0.4064)
			(end 0.7874 -0.4064)
			(stroke
				(width 0.1524)
				(type default)
			)
			(layer "F.SilkS")
		)
		(fp_line
			(start 0.67945 0.3048)
			(end 0.120396 0.3048)
			(stroke
				(width 0.1)
				(type default)
			)
			(layer "F.Fab")
		)
		(fp_line
			(start 0.67945 -0.3048)
			(end 0.67945 0.3048)
			(stroke
				(width 0.1)
				(type default)
			)
			(layer "F.Fab")
		)
		(fp_line
			(start 0.12065 -0.2794)
			(end 0.12065 -0.3048)
			(stroke
				(width 0.1)
				(type default)
			)
			(layer "F.Fab")
		)
		(fp_line
			(start 0.12065 -0.3048)
			(end 0.67945 -0.3048)
			(stroke
				(width 0.1)
				(type default)
			)
			(layer "F.Fab")
		)
		(fp_line
			(start 0.120396 0.3048)
			(end 0.120396 0.2794)
			(stroke
				(width 0.1)
				(type default)
			)
			(layer "F.Fab")
		)
		(fp_line
			(start 0.120396 0.2794)
			(end -0.12065 0.2794)
			(stroke
				(width 0.1)
				(type default)
			)
			(layer "F.Fab")
		)
		(fp_line
			(start -0.12065 0.3048)
			(end -0.67945 0.3048)
			(stroke
				(width 0.1)
				(type default)
			)
			(layer "F.Fab")
		)
		(fp_line
			(start -0.12065 0.2794)
			(end -0.12065 0.3048)
			(stroke
				(width 0.1)
				(type default)
			)
			(layer "F.Fab")
		)
		(fp_line
			(start -0.12065 -0.2794)
			(end 0.12065 -0.2794)
			(stroke
				(width 0.1)
				(type default)
			)
			(layer "F.Fab")
		)
		(fp_line
			(start -0.12065 -0.305054)
			(end -0.12065 -0.2794)
			(stroke
				(width 0.1)
				(type default)
			)
			(layer "F.Fab")
		)
		(fp_line
			(start -0.67945 0.3048)
			(end -0.67945 -0.305054)
			(stroke
				(width 0.1)
				(type default)
			)
			(layer "F.Fab")
		)
		(fp_line
			(start -0.67945 -0.305054)
			(end -0.12065 -0.305054)
			(stroke
				(width 0.1)
				(type default)
			)
			(layer "F.Fab")
		)
		(pad "1" smd circle
			(at -0.40005 0 180)
			(size 0 0)
			(layers "F.Cu" "F.Mask" "F.Paste")
			(net "GPU_FPGA_EROT_RST_N")
		)
		(pad "2" smd circle
			(at 0.40005 0 180)
			(size 0 0)
			(layers "F.Cu" "F.Mask" "F.Paste")
			(net "GPU_FPGA_EROT_RST_R_N")
		)
	)
	(footprint ""
		(layer "F.Cu")
		(at 240.298224 -159.680148)
		(property "Reference" "R6110"
			(at 0 0 0)
			(layer "F.SilkS")
			(hide yes)
			(effects
				(font
					(size 1.27 1.27)
				)
			)
		)
		(property "Value" ""
			(at 0 0 0)
			(layer "F.Fab")
			(effects
				(font
					(size 1.27 1.27)
				)
			)
		)
		(duplicate_pad_numbers_are_jumpers no)
		(fp_line
			(start -0.7874 -0.4064)
			(end 0.7874 -0.4064)
			(stroke
				(width 0.1524)
				(type default)
			)
			(layer "F.SilkS")
		)
		(fp_line
			(start -0.7874 0.4064)
			(end -0.7874 -0.4064)
			(stroke
				(width 0.1524)
				(type default)
			)
			(layer "F.SilkS")
		)
		(fp_line
			(start 0.7874 -0.4064)
			(end 0.7874 0.4064)
			(stroke
				(width 0.1524)
				(type default)
			)
			(layer "F.SilkS")
		)
		(fp_line
			(start 0.7874 0.4064)
			(end -0.7874 0.4064)
			(stroke
				(width 0.1524)
				(type default)
			)
			(layer "F.SilkS")
		)
		(fp_line
			(start -0.67945 -0.305054)
			(end -0.12065 -0.305054)
			(stroke
				(width 0.1)
				(type default)
			)
			(layer "F.Fab")
		)
		(fp_line
			(start -0.67945 0.3048)
			(end -0.67945 -0.305054)
			(stroke
				(width 0.1)
				(type default)
			)
			(layer "F.Fab")
		)
		(fp_line
			(start -0.12065 -0.305054)
			(end -0.12065 -0.2794)
			(stroke
				(width 0.1)
				(type default)
			)
			(layer "F.Fab")
		)
		(fp_line
			(start -0.12065 -0.2794)
			(end 0.12065 -0.2794)
			(stroke
				(width 0.1)
				(type default)
			)
			(layer "F.Fab")
		)
		(fp_line
			(start -0.12065 0.2794)
			(end -0.12065 0.3048)
			(stroke
				(width 0.1)
				(type default)
			)
			(layer "F.Fab")
		)
		(fp_line
			(start -0.12065 0.3048)
			(end -0.67945 0.3048)
			(stroke
				(width 0.1)
				(type default)
			)
			(layer "F.Fab")
		)
		(fp_line
			(start 0.120396 0.2794)
			(end -0.12065 0.2794)
			(stroke
				(width 0.1)
				(type default)
			)
			(layer "F.Fab")
		)
		(fp_line
			(start 0.120396 0.3048)
			(end 0.120396 0.2794)
			(stroke
				(width 0.1)
				(type default)
			)
			(layer "F.Fab")
		)
		(fp_line
			(start 0.12065 -0.3048)
			(end 0.67945 -0.3048)
			(stroke
				(width 0.1)
				(type default)
			)
			(layer "F.Fab")
		)
		(fp_line
			(start 0.12065 -0.2794)
			(end 0.12065 -0.3048)
			(stroke
				(width 0.1)
				(type default)
			)
			(layer "F.Fab")
		)
		(fp_line
			(start 0.67945 -0.3048)
			(end 0.67945 0.3048)
			(stroke
				(width 0.1)
				(type default)
			)
			(layer "F.Fab")
		)
		(fp_line
			(start 0.67945 0.3048)
			(end 0.120396 0.3048)
			(stroke
				(width 0.1)
				(type default)
			)
			(layer "F.Fab")
		)
		(pad "1" smd circle
			(at -0.40005 0)
			(size 0 0)
			(layers "F.Cu" "F.Mask" "F.Paste")
			(net "JTAG_CPUX_TDO_R")
		)
		(pad "2" smd circle
			(at 0.40005 0)
			(size 0 0)
			(layers "F.Cu" "F.Mask" "F.Paste")
			(net "JTAG_CPUX_TDO")
		)
	)
	(footprint ""
		(layer "F.Cu")
		(at 149.478746 -408.517344 -90)
		(property "Reference" "C6715"
			(at 0 0 270)
			(layer "F.SilkS")
			(hide yes)
			(effects
				(font
					(size 1.27 1.27)
				)
			)
		)
		(property "Value" ""
			(at 0 0 270)
			(layer "F.Fab")
			(effects
				(font
					(size 1.27 1.27)
				)
			)
		)
		(duplicate_pad_numbers_are_jumpers no)
		(fp_line
			(start -0.299974 0.150114)
			(end -0.299974 -0.150114)
			(stroke
				(width 0.1)
				(type default)
			)
			(layer "F.Fab")
		)
		(fp_line
			(start 0.299974 0.150114)
			(end -0.299974 0.150114)
			(stroke
				(width 0.1)
				(type default)
			)
			(layer "F.Fab")
		)
		(fp_line
			(start -0.299974 -0.150114)
			(end 0.299974 -0.150114)
			(stroke
				(width 0.1)
				(type default)
			)
			(layer "F.Fab")
		)
		(fp_line
			(start 0.299974 -0.150114)
			(end 0.299974 0.150114)
			(stroke
				(width 0.1)
				(type default)
			)
			(layer "F.Fab")
		)
		(pad "1" smd rect
			(at -0.2667 0 270)
			(size 0.3048 0.381)
			(layers "F.Cu" "F.Mask" "F.Paste")
			(net "P5E_CPU1_P2_TX_BUF_C_DP<11>")
		)
		(pad "2" smd rect
			(at 0.2667 0 270)
			(size 0.3048 0.381)
			(layers "F.Cu" "F.Mask" "F.Paste")
			(net "P5E_CPU1_P2_TX_BUF_DP<11>")
		)
	)
)
